# BASEBOARD_FAB2 (Tioga Pass) — schematic netlist excerpt (pin names and nets, part order shuffled) for the footprints in the layout excerpt that follows; sources: Cadence DE-HDL packaged netlist, KiCad conversion of Wiwynn_Tioga_Pass_MB.brd

U14E3  TTL1G08  NC7SZ08 IC  pkg SOTLF  page 248
  A(0)  = PWRGD_P12V_HSC_DLY
  B(0)  = PWRGD_P3V3
  Y(0)  = RST_PCIE_M2_DEV_AND

C9G4  CAP_A  0.1UF 16V 10% X7R  pkg 0402V  page 141 : A = GND_LAN_TRCT1234_C ; B = GND
C5D37  CAP_A  22.0UF 4V 20% X6S  pkg 0603V  page 42 : A = PVCCMCP_CPU0 ; B = GND

(kicad_pcb
	(version 20260206)
	(generator "pcbnew")
	(generator_version "10.0")
	(general
		(thickness 1.6)
		(legacy_teardrops no)
	)
	(paper "A4")
	(title_block
		(title "Wiwynn_Tioga_Pass_MB.brd")
		(comment 1 "Tioga Pass / footprints 725-727 of 4770")
	)
	(layers
		(0 "F.Cu" signal "TOP")
		(4 "In1.Cu" signal "L2GND")
		(6 "In2.Cu" signal "L3")
		(8 "In3.Cu" signal "L4GND")
		(10 "In4.Cu" signal "L5")
		(12 "In5.Cu" signal "L6GND")
		(14 "In6.Cu" signal "L7VCC")
		(16 "In7.Cu" signal "L8VCC")
		(18 "In8.Cu" signal "L9GND")
		(20 "In9.Cu" signal "L10")
		(22 "In10.Cu" signal "L11GND")
		(24 "In11.Cu" signal "L12")
		(26 "In12.Cu" signal "L13GND")
		(2 "B.Cu" signal "BOTTOM")
		(9 "F.Adhes" user "F.Adhesive")
		(11 "B.Adhes" user "B.Adhesive")
		(13 "F.Paste" user "Package Geometry/Pastemask Top")
		(15 "B.Paste" user "Package Geometry/Pastemask Bottom")
		(5 "F.SilkS" user "Ref Des/Silkscreen Top")
		(7 "B.SilkS" user "Ref Des/Silkscreen Bottom")
		(1 "F.Mask" user "Board Geometry/Soldermask Top")
		(3 "B.Mask" user "Board Geometry/Soldermask Bottom")
		(17 "Dwgs.User" user "User.Drawings")
		(19 "Cmts.User" user "User.Comments")
		(21 "Eco1.User" user "User.Eco1")
		(23 "Eco2.User" user "User.Eco2")
		(25 "Edge.Cuts" user "Board Geometry/Outline")
		(27 "Margin" user)
		(31 "F.CrtYd" user "Package Geometry/Place Bound Top")
		(29 "B.CrtYd" user "Package Geometry/Place Bound Bottom")
		(35 "F.Fab" user "Ref Des/Assembly Top")
		(33 "B.Fab" user "Ref Des/Assembly Bottom")
	)
	(footprint ""
		(layer "F.Cu")
		(at 386.464302 -83.223608)
		(property "Reference" "U14E3"
			(at -0.14986 2.621788 0)
			(unlocked yes)
			(layer "F.SilkS")
			(effects
				(font
					(size 1.27 0.964946)
					(thickness 0.000001)
				)
				(justify left)
			)
		)
		(property "Value" ""
			(at 0 0 0)
			(layer "F.Fab")
			(effects
				(font
					(size 1.27 1.27)
				)
			)
		)
		(duplicate_pad_numbers_are_jumpers no)
		(fp_circle
			(center -0.4699 -0.8382)
			(end -0.3429 -0.8382)
			(stroke
				(width 0.254)
				(type default)
			)
			(fill no)
			(layer "F.SilkS")
		)
		(fp_poly
			(pts
				(xy 0.21463 -0.450088) (xy 1.56337 -0.450088) (xy 1.56337 1.75006) (xy 0.21463 1.75006)
			)
			(stroke
				(width 0)
				(type default)
			)
			(fill no)
			(layer "F.CrtYd")
		)
		(fp_line
			(start 0.21463 -0.450088)
			(end 1.56337 -0.450088)
			(stroke
				(width 0.1)
				(type default)
			)
			(layer "F.Fab")
		)
		(fp_line
			(start 0.21463 1.75006)
			(end 0.21463 -0.450088)
			(stroke
				(width 0.1)
				(type default)
			)
			(layer "F.Fab")
		)
		(fp_line
			(start 1.56337 -0.450088)
			(end 1.56337 1.75006)
			(stroke
				(width 0.1)
				(type default)
			)
			(layer "F.Fab")
		)
		(fp_line
			(start 1.56337 1.75006)
			(end 0.21463 1.75006)
			(stroke
				(width 0.1)
				(type default)
			)
			(layer "F.Fab")
		)
		(fp_circle
			(center -0.4699 -0.8382)
			(end -0.3429 -0.8382)
			(stroke
				(width 0.254)
				(type default)
			)
			(fill no)
			(layer "F.Fab")
		)
		(pad "1" smd rect
			(at 0 0)
			(size 1.016 0.381)
			(layers "F.Cu" "F.Mask" "F.Paste")
			(net "PWRGD_P12V_HSC_DLY")
		)
		(pad "2" smd rect
			(at 0 0.649986)
			(size 1.016 0.381)
			(layers "F.Cu" "F.Mask" "F.Paste")
			(net "PWRGD_P3V3")
		)
		(pad "3" smd rect
			(at 0 1.299972)
			(size 1.016 0.381)
			(layers "F.Cu" "F.Mask" "F.Paste")
			(net "GND")
		)
		(pad "4" smd rect
			(at 1.778 1.299972)
			(size 1.016 0.381)
			(layers "F.Cu" "F.Mask" "F.Paste")
			(net "RST_PCIE_M2_DEV_AND")
		)
		(pad "5" smd rect
			(at 1.778 0)
			(size 1.016 0.381)
			(layers "F.Cu" "F.Mask" "F.Paste")
			(net "P3V3")
		)
	)
	(footprint ""
		(layer "F.Cu")
		(at 478.30486 -18.48739)
		(property "Reference" "C9G4"
			(at 0 0 0)
			(layer "F.SilkS")
			(hide yes)
			(effects
				(font
					(size 1.27 1.27)
				)
			)
		)
		(property "Value" ""
			(at 0 0 0)
			(layer "F.Fab")
			(effects
				(font
					(size 1.27 1.27)
				)
			)
		)
		(duplicate_pad_numbers_are_jumpers no)
		(fp_poly
			(pts
				(xy 0.3048 -0.1016) (xy 0.3048 0.9906) (xy -0.3048 0.9906) (xy -0.3048 -0.1016)
			)
			(stroke
				(width 0)
				(type default)
			)
			(fill no)
			(layer "F.CrtYd")
		)
		(fp_line
			(start -0.3048 -0.1016)
			(end -0.3048 0.9906)
			(stroke
				(width 0.1)
				(type default)
			)
			(layer "F.Fab")
		)
		(fp_line
			(start -0.3048 0.9906)
			(end 0.3048 0.9906)
			(stroke
				(width 0.1)
				(type default)
			)
			(layer "F.Fab")
		)
		(fp_line
			(start 0.3048 -0.1016)
			(end -0.3048 -0.1016)
			(stroke
				(width 0.1)
				(type default)
			)
			(layer "F.Fab")
		)
		(fp_line
			(start 0.3048 0.9906)
			(end 0.3048 -0.1016)
			(stroke
				(width 0.1)
				(type default)
			)
			(layer "F.Fab")
		)
		(pad "1" smd rect
			(at 0 0)
			(size 0.508 0.508)
			(layers "F.Cu" "F.Mask" "F.Paste")
			(net "GND_LAN_TRCT1234_C")
		)
		(pad "2" smd rect
			(at 0 0.889)
			(size 0.508 0.508)
			(layers "F.Cu" "F.Mask" "F.Paste")
			(net "GND")
		)
		(zone
			(layer "F.Cu")
			(hatch none 0.5)
			(connect_pads
				(clearance 0)
			)
			(min_thickness 0.25)
			(keepout
				(tracks allowed)
				(vias not_allowed)
				(pads allowed)
				(copperpour not_allowed)
				(footprints allowed)
			)
			(placement
				(enabled no)
				(sheetname "")
			)
			(fill
				(thermal_gap 0.5)
				(thermal_bridge_width 0.5)
				(island_removal_mode 0)
			)
			(polygon
				(pts
					(xy 478.05086 -18.23339) (xy 478.55886 -18.23339) (xy 478.55886 -17.85239) (xy 478.05086 -17.85239)
				)
			)
		)
		(zone
			(layer "F.Cu")
			(hatch none 0.5)
			(connect_pads
				(clearance 0)
			)
			(min_thickness 0.25)
			(keepout
				(tracks not_allowed)
				(vias allowed)
				(pads allowed)
				(copperpour not_allowed)
				(footprints allowed)
			)
			(placement
				(enabled no)
				(sheetname "")
			)
			(fill
				(thermal_gap 0.5)
				(thermal_bridge_width 0.5)
				(island_removal_mode 0)
			)
			(polygon
				(pts
					(xy 478.05086 -17.85239) (xy 478.55886 -17.85239) (xy 478.55886 -18.23339) (xy 478.05086 -18.23339)
				)
			)
		)
	)
	(footprint ""
		(layer "F.Cu")
		(at 274.639024 -77.429614)
		(property "Reference" "C5D37"
			(at 0 0 0)
			(layer "F.SilkS")
			(hide yes)
			(effects
				(font
					(size 1.27 1.27)
				)
			)
		)
		(property "Value" ""
			(at 0 0 0)
			(layer "F.Fab")
			(effects
				(font
					(size 1.27 1.27)
				)
			)
		)
		(duplicate_pad_numbers_are_jumpers no)
		(fp_poly
			(pts
				(xy -0.4953 -0.2032) (xy 0.4953 -0.2032) (xy 0.4953 1.6002) (xy -0.4953 1.6002)
			)
			(stroke
				(width 0)
				(type default)
			)
			(fill no)
			(layer "F.CrtYd")
		)
		(fp_line
			(start -0.4953 -0.2032)
			(end 0.4953 -0.2032)
			(stroke
				(width 0.1)
				(type default)
			)
			(layer "F.Fab")
		)
		(fp_line
			(start -0.4953 1.6002)
			(end -0.4953 -0.2032)
			(stroke
				(width 0.1)
				(type default)
			)
			(layer "F.Fab")
		)
		(fp_line
			(start 0.4953 -0.2032)
			(end 0.4953 1.6002)
			(stroke
				(width 0.1)
				(type default)
			)
			(layer "F.Fab")
		)
		(fp_line
			(start 0.4953 1.6002)
			(end -0.4953 1.6002)
			(stroke
				(width 0.1)
				(type default)
			)
			(layer "F.Fab")
		)
		(pad "1" smd rect
			(at 0 0)
			(size 0.762 0.889)
			(layers "F.Cu" "F.Mask" "F.Paste")
			(net "PVCCMCP_CPU0")
		)
		(pad "2" smd rect
			(at 0 1.397)
			(size 0.762 0.889)
			(layers "F.Cu" "F.Mask" "F.Paste")
			(net "GND")
		)
		(zone
			(layer "F.Cu")
			(hatch none 0.5)
			(connect_pads
				(clearance 0)
			)
			(min_thickness 0.25)
			(keepout
				(tracks not_allowed)
				(vias allowed)
				(pads allowed)
				(copperpour not_allowed)
				(footprints allowed)
			)
			(placement
				(enabled no)
				(sheetname "")
			)
			(fill
				(thermal_gap 0.5)
				(thermal_bridge_width 0.5)
				(island_removal_mode 0)
			)
			(polygon
				(pts
					(xy 274.258024 -76.985114) (xy 275.020024 -76.985114) (xy 275.020024 -76.477114) (xy 274.258024 -76.477114)
				)
			)
		)
	)
)
